FILE_TYPE=LIBRARY_PARTS;
primitive 'PRTR5V0U2X';
  pin
    'IO1':
      PIN_NUMBER='(2)';
      BIDIRECTIONAL='TRUE';
      INPUT_LOAD='(-0.01,0.01)';
      OUTPUT_LOAD='(1.0,-1.0)';
    'GND':
      PIN_NUMBER='(1)';
      PINUSE='POWER';
      NO_LOAD_CHECK='Both';
      NO_IO_CHECK='Both';
      NO_ASSERT_CHECK='TRUE';
      NO_DIR_CHECK='TRUE';
      ALLOW_CONNECT='TRUE';
    'VCC':
      PIN_NUMBER='(4)';
      PINUSE='POWER';
      NO_LOAD_CHECK='Both';
      NO_IO_CHECK='Both';
      NO_ASSERT_CHECK='TRUE';
      NO_DIR_CHECK='TRUE';
      ALLOW_CONNECT='TRUE';
    'IO2':
      PIN_NUMBER='(3)';
      BIDIRECTIONAL='TRUE';
      INPUT_LOAD='(-0.01,0.01)';
      OUTPUT_LOAD='(1.0,-1.0)';
  end_pin;
  body
    PART_NAME='PRTR5V0U2X';
    BODY_NAME='PRTR5V0U2X';
    PHYS_DES_PREFIX='U';
    CLASS='IC';
  end_body;
end_primitive;

END.
